# S9S_MB_2U (Grand Teton) — schematic netlist excerpt (pin names and nets, part order shuffled) for the footprints in the layout excerpt that follows; sources: Cadence DE-HDL packaged netlist, KiCad conversion of 03242023_DA0F0TMBIJ0_F0T_Motherboard_J_brd_V01_OCP.brd

R1375  Q_RES  10K 1% CHIP  pkg 0402LF  page 134 : A = FM_BMC_EN_DET ; B = GND
C1576  Q_CAP_DIFFBUS  DIFF BUS_0.22UF 6.3V 20% X6S  pkg C0201  page 175 : \1\ = P5E_CPU0_PE4_TX_C_DN<1> ; \2\ = P5E_CPU0_PE4_TX_DN<1>
PR1101  Q_RES  2K 0.1% CHIP  pkg 0402LF  page 302 : A = HSC_IMON ; B = AGND_HSC

(kicad_pcb
	(version 20260206)
	(generator "pcbnew")
	(generator_version "10.0")
	(general
		(thickness 1.6)
		(legacy_teardrops no)
	)
	(paper "A4")
	(title_block
		(title "03242023_DA0F0TMBIJ0_F0T_Motherboard_J_brd_V01_OCP.brd")
		(comment 1 "Grand Teton / footprints 1870-1872 of 6105")
	)
	(layers
		(0 "F.Cu" signal "TOP")
		(4 "In1.Cu" signal "GND")
		(6 "In2.Cu" signal "IN1")
		(8 "In3.Cu" signal "GND1")
		(10 "In4.Cu" signal "IN2")
		(12 "In5.Cu" signal "GND2")
		(14 "In6.Cu" signal "IN3")
		(16 "In7.Cu" signal "GND3")
		(18 "In8.Cu" signal "VCC")
		(20 "In9.Cu" signal "VCC1")
		(22 "In10.Cu" signal "GND4")
		(24 "In11.Cu" signal "IN4")
		(26 "In12.Cu" signal "GND5")
		(28 "In13.Cu" signal "IN5")
		(30 "In14.Cu" signal "GND6")
		(32 "In15.Cu" signal "IN6")
		(34 "In16.Cu" signal "GND7")
		(2 "B.Cu" signal "BOTTOM")
		(9 "F.Adhes" user "F.Adhesive")
		(11 "B.Adhes" user "B.Adhesive")
		(13 "F.Paste" user "Package Geometry/Pastemask Top")
		(15 "B.Paste" user "Package Geometry/Pastemask Bottom")
		(5 "F.SilkS" user "Ref Des/Silkscreen Top")
		(7 "B.SilkS" user "Ref Des/Silkscreen Bottom")
		(1 "F.Mask" user "Board Geometry/Soldermask Top")
		(3 "B.Mask" user "Board Geometry/Soldermask Bottom")
		(17 "Dwgs.User" user "User.Drawings")
		(19 "Cmts.User" user "User.Comments")
		(21 "Eco1.User" user "User.Eco1")
		(23 "Eco2.User" user "User.Eco2")
		(25 "Edge.Cuts" user "Board Geometry/Outline")
		(27 "Margin" user)
		(31 "F.CrtYd" user "Package Geometry/Place Bound Top")
		(29 "B.CrtYd" user "Package Geometry/Place Bound Bottom")
		(35 "F.Fab" user "Ref Des/Assembly Top")
		(33 "B.Fab" user "Ref Des/Assembly Bottom")
	)
	(footprint ""
		(layer "F.Cu")
		(at 205.397608 -402.791422 180)
		(property "Reference" "PR1101"
			(at 0 0 180)
			(layer "F.SilkS")
			(hide yes)
			(effects
				(font
					(size 1.27 1.27)
				)
			)
		)
		(property "Value" ""
			(at 0 0 180)
			(layer "F.Fab")
			(effects
				(font
					(size 1.27 1.27)
				)
			)
		)
		(duplicate_pad_numbers_are_jumpers no)
		(fp_line
			(start 0.7874 0.4064)
			(end -0.7874 0.4064)
			(stroke
				(width 0.1524)
				(type default)
			)
			(layer "F.SilkS")
		)
		(fp_line
			(start 0.7874 -0.4064)
			(end 0.7874 0.4064)
			(stroke
				(width 0.1524)
				(type default)
			)
			(layer "F.SilkS")
		)
		(fp_line
			(start -0.7874 0.4064)
			(end -0.7874 -0.4064)
			(stroke
				(width 0.1524)
				(type default)
			)
			(layer "F.SilkS")
		)
		(fp_line
			(start -0.7874 -0.4064)
			(end 0.7874 -0.4064)
			(stroke
				(width 0.1524)
				(type default)
			)
			(layer "F.SilkS")
		)
		(fp_line
			(start 0.67945 0.3048)
			(end 0.120396 0.3048)
			(stroke
				(width 0.1)
				(type default)
			)
			(layer "F.Fab")
		)
		(fp_line
			(start 0.67945 -0.3048)
			(end 0.67945 0.3048)
			(stroke
				(width 0.1)
				(type default)
			)
			(layer "F.Fab")
		)
		(fp_line
			(start 0.12065 -0.2794)
			(end 0.12065 -0.3048)
			(stroke
				(width 0.1)
				(type default)
			)
			(layer "F.Fab")
		)
		(fp_line
			(start 0.12065 -0.3048)
			(end 0.67945 -0.3048)
			(stroke
				(width 0.1)
				(type default)
			)
			(layer "F.Fab")
		)
		(fp_line
			(start 0.120396 0.3048)
			(end 0.120396 0.2794)
			(stroke
				(width 0.1)
				(type default)
			)
			(layer "F.Fab")
		)
		(fp_line
			(start 0.120396 0.2794)
			(end -0.12065 0.2794)
			(stroke
				(width 0.1)
				(type default)
			)
			(layer "F.Fab")
		)
		(fp_line
			(start -0.12065 0.3048)
			(end -0.67945 0.3048)
			(stroke
				(width 0.1)
				(type default)
			)
			(layer "F.Fab")
		)
		(fp_line
			(start -0.12065 0.2794)
			(end -0.12065 0.3048)
			(stroke
				(width 0.1)
				(type default)
			)
			(layer "F.Fab")
		)
		(fp_line
			(start -0.12065 -0.2794)
			(end 0.12065 -0.2794)
			(stroke
				(width 0.1)
				(type default)
			)
			(layer "F.Fab")
		)
		(fp_line
			(start -0.12065 -0.305054)
			(end -0.12065 -0.2794)
			(stroke
				(width 0.1)
				(type default)
			)
			(layer "F.Fab")
		)
		(fp_line
			(start -0.67945 0.3048)
			(end -0.67945 -0.305054)
			(stroke
				(width 0.1)
				(type default)
			)
			(layer "F.Fab")
		)
		(fp_line
			(start -0.67945 -0.305054)
			(end -0.12065 -0.305054)
			(stroke
				(width 0.1)
				(type default)
			)
			(layer "F.Fab")
		)
		(pad "1" smd circle
			(at -0.40005 0 180)
			(size 0 0)
			(layers "F.Cu" "F.Mask" "F.Paste")
			(net "HSC_IMON")
		)
		(pad "2" smd circle
			(at 0.40005 0 180)
			(size 0 0)
			(layers "F.Cu" "F.Mask" "F.Paste")
			(net "AGND_HSC")
		)
	)
	(footprint ""
		(layer "F.Cu")
		(at 307.932328 -402.371052 -90)
		(property "Reference" "C1576"
			(at 0 0 270)
			(layer "F.SilkS")
			(hide yes)
			(effects
				(font
					(size 1.27 1.27)
				)
			)
		)
		(property "Value" ""
			(at 0 0 270)
			(layer "F.Fab")
			(effects
				(font
					(size 1.27 1.27)
				)
			)
		)
		(duplicate_pad_numbers_are_jumpers no)
		(fp_line
			(start -0.299974 0.150114)
			(end -0.299974 -0.150114)
			(stroke
				(width 0.1)
				(type default)
			)
			(layer "F.Fab")
		)
		(fp_line
			(start 0.299974 0.150114)
			(end -0.299974 0.150114)
			(stroke
				(width 0.1)
				(type default)
			)
			(layer "F.Fab")
		)
		(fp_line
			(start -0.299974 -0.150114)
			(end 0.299974 -0.150114)
			(stroke
				(width 0.1)
				(type default)
			)
			(layer "F.Fab")
		)
		(fp_line
			(start 0.299974 -0.150114)
			(end 0.299974 0.150114)
			(stroke
				(width 0.1)
				(type default)
			)
			(layer "F.Fab")
		)
		(pad "1" smd rect
			(at -0.2667 0 270)
			(size 0.3048 0.381)
			(layers "F.Cu" "F.Mask" "F.Paste")
			(net "P5E_CPU0_PE4_TX_C_DN<1>")
		)
		(pad "2" smd rect
			(at 0.2667 0 270)
			(size 0.3048 0.381)
			(layers "F.Cu" "F.Mask" "F.Paste")
			(net "P5E_CPU0_PE4_TX_DN<1>")
		)
	)
	(footprint ""
		(layer "F.Cu")
		(at 96.57588 -54.066948 180)
		(property "Reference" "R1375"
			(at 0 0 180)
			(layer "F.SilkS")
			(hide yes)
			(effects
				(font
					(size 1.27 1.27)
				)
			)
		)
		(property "Value" ""
			(at 0 0 180)
			(layer "F.Fab")
			(effects
				(font
					(size 1.27 1.27)
				)
			)
		)
		(duplicate_pad_numbers_are_jumpers no)
		(fp_line
			(start 0.7874 0.4064)
			(end -0.7874 0.4064)
			(stroke
				(width 0.1524)
				(type default)
			)
			(layer "F.SilkS")
		)
		(fp_line
			(start 0.7874 -0.4064)
			(end 0.7874 0.4064)
			(stroke
				(width 0.1524)
				(type default)
			)
			(layer "F.SilkS")
		)
		(fp_line
			(start -0.7874 0.4064)
			(end -0.7874 -0.4064)
			(stroke
				(width 0.1524)
				(type default)
			)
			(layer "F.SilkS")
		)
		(fp_line
			(start -0.7874 -0.4064)
			(end 0.7874 -0.4064)
			(stroke
				(width 0.1524)
				(type default)
			)
			(layer "F.SilkS")
		)
		(fp_line
			(start 0.67945 0.3048)
			(end 0.120396 0.3048)
			(stroke
				(width 0.1)
				(type default)
			)
			(layer "F.Fab")
		)
		(fp_line
			(start 0.67945 -0.3048)
			(end 0.67945 0.3048)
			(stroke
				(width 0.1)
				(type default)
			)
			(layer "F.Fab")
		)
		(fp_line
			(start 0.12065 -0.2794)
			(end 0.12065 -0.3048)
			(stroke
				(width 0.1)
				(type default)
			)
			(layer "F.Fab")
		)
		(fp_line
			(start 0.12065 -0.3048)
			(end 0.67945 -0.3048)
			(stroke
				(width 0.1)
				(type default)
			)
			(layer "F.Fab")
		)
		(fp_line
			(start 0.120396 0.3048)
			(end 0.120396 0.2794)
			(stroke
				(width 0.1)
				(type default)
			)
			(layer "F.Fab")
		)
		(fp_line
			(start 0.120396 0.2794)
			(end -0.12065 0.2794)
			(stroke
				(width 0.1)
				(type default)
			)
			(layer "F.Fab")
		)
		(fp_line
			(start -0.12065 0.3048)
			(end -0.67945 0.3048)
			(stroke
				(width 0.1)
				(type default)
			)
			(layer "F.Fab")
		)
		(fp_line
			(start -0.12065 0.2794)
			(end -0.12065 0.3048)
			(stroke
				(width 0.1)
				(type default)
			)
			(layer "F.Fab")
		)
		(fp_line
			(start -0.12065 -0.2794)
			(end 0.12065 -0.2794)
			(stroke
				(width 0.1)
				(type default)
			)
			(layer "F.Fab")
		)
		(fp_line
			(start -0.12065 -0.305054)
			(end -0.12065 -0.2794)
			(stroke
				(width 0.1)
				(type default)
			)
			(layer "F.Fab")
		)
		(fp_line
			(start -0.67945 0.3048)
			(end -0.67945 -0.305054)
			(stroke
				(width 0.1)
				(type default)
			)
			(layer "F.Fab")
		)
		(fp_line
			(start -0.67945 -0.305054)
			(end -0.12065 -0.305054)
			(stroke
				(width 0.1)
				(type default)
			)
			(layer "F.Fab")
		)
		(pad "1" smd circle
			(at -0.40005 0 180)
			(size 0 0)
			(layers "F.Cu" "F.Mask" "F.Paste")
			(net "FM_BMC_EN_DET")
		)
		(pad "2" smd circle
			(at 0.40005 0 180)
			(size 0 0)
			(layers "F.Cu" "F.Mask" "F.Paste")
			(net "GND")
		)
	)
)
